# T6G (Grand Teton) — schematic netlist excerpt (pin names and nets, part order shuffled) for the footprints in the layout excerpt that follows; sources: Cadence DE-HDL packaged netlist, KiCad conversion of 04192023_DAF0TMB3IC0_F0TG_MB_C_brd_V02_OCP.brd

R116  Q_RES  33 5% CHIP  pkg 0402LF  page 155 : A = IRQ_OCP_SFF_WAKE_BUF_N ; B = IRQ_LVC3_WAKE_N
C6504  Q_CAP_DIFFBUS  DIFF BUS_0.22UF 6.3V 20% X6S  pkg C0201  page 275 : \1\ = P5E_CPU0_P0_TX_BUF_C_DN<1> ; \2\ = P5E_CPU0_P0_TX_BUF_DN<1>
PC2151  Q_CAP  6800PF 50V 10% X7R  pkg C0402  page 140 : A = P3V3_OCP_GATE_2 ; B = GND

(kicad_pcb
	(version 20260206)
	(generator "pcbnew")
	(generator_version "10.0")
	(general
		(thickness 1.6)
		(legacy_teardrops no)
	)
	(paper "A4")
	(title_block
		(title "04192023_DAF0TMB3IC0_F0TG_MB_C_brd_V02_OCP.brd")
		(comment 1 "Grand Teton / footprints 2995-2997 of 8354")
	)
	(layers
		(0 "F.Cu" signal "TOP")
		(4 "In1.Cu" signal "GND")
		(6 "In2.Cu" signal "IN1")
		(8 "In3.Cu" signal "GND1")
		(10 "In4.Cu" signal "IN2")
		(12 "In5.Cu" signal "GND2")
		(14 "In6.Cu" signal "IN3")
		(16 "In7.Cu" signal "GND3")
		(18 "In8.Cu" signal "VCC")
		(20 "In9.Cu" signal "VCC1")
		(22 "In10.Cu" signal "GND4")
		(24 "In11.Cu" signal "IN4")
		(26 "In12.Cu" signal "GND5")
		(28 "In13.Cu" signal "IN5")
		(30 "In14.Cu" signal "GND6")
		(32 "In15.Cu" signal "IN6")
		(34 "In16.Cu" signal "GND7")
		(2 "B.Cu" signal "BOTTOM")
		(9 "F.Adhes" user "F.Adhesive")
		(11 "B.Adhes" user "B.Adhesive")
		(13 "F.Paste" user "Package Geometry/Pastemask Top")
		(15 "B.Paste" user "Package Geometry/Pastemask Bottom")
		(5 "F.SilkS" user "Ref Des/Silkscreen Top")
		(7 "B.SilkS" user "Ref Des/Silkscreen Bottom")
		(1 "F.Mask" user "Board Geometry/Soldermask Top")
		(3 "B.Mask" user "Board Geometry/Soldermask Bottom")
		(17 "Dwgs.User" user "User.Drawings")
		(19 "Cmts.User" user "User.Comments")
		(21 "Eco1.User" user "User.Eco1")
		(23 "Eco2.User" user "User.Eco2")
		(25 "Edge.Cuts" user "Board Geometry/Outline")
		(27 "Margin" user)
		(31 "F.CrtYd" user "Package Geometry/Place Bound Top")
		(29 "B.CrtYd" user "Package Geometry/Place Bound Bottom")
		(35 "F.Fab" user "Ref Des/Assembly Top")
		(33 "B.Fab" user "Ref Des/Assembly Bottom")
	)
	(footprint ""
		(layer "F.Cu")
		(at 89.898982 -55.713122 180)
		(property "Reference" "PC2151"
			(at 0 0 180)
			(layer "F.SilkS")
			(hide yes)
			(effects
				(font
					(size 1.27 1.27)
				)
			)
		)
		(property "Value" ""
			(at 0 0 180)
			(layer "F.Fab")
			(effects
				(font
					(size 1.27 1.27)
				)
			)
		)
		(duplicate_pad_numbers_are_jumpers no)
		(fp_line
			(start 0.7874 0.4064)
			(end -0.7874 0.4064)
			(stroke
				(width 0.1524)
				(type default)
			)
			(layer "F.SilkS")
		)
		(fp_line
			(start 0.7874 -0.4064)
			(end 0.7874 0.4064)
			(stroke
				(width 0.1524)
				(type default)
			)
			(layer "F.SilkS")
		)
		(fp_line
			(start -0.7874 0.4064)
			(end -0.7874 -0.4064)
			(stroke
				(width 0.1524)
				(type default)
			)
			(layer "F.SilkS")
		)
		(fp_line
			(start -0.7874 -0.4064)
			(end 0.7874 -0.4064)
			(stroke
				(width 0.1524)
				(type default)
			)
			(layer "F.SilkS")
		)
		(fp_line
			(start 0.67945 0.3048)
			(end 0.120396 0.3048)
			(stroke
				(width 0.1)
				(type default)
			)
			(layer "F.Fab")
		)
		(fp_line
			(start 0.67945 -0.3048)
			(end 0.67945 0.3048)
			(stroke
				(width 0.1)
				(type default)
			)
			(layer "F.Fab")
		)
		(fp_line
			(start 0.12065 -0.2794)
			(end 0.12065 -0.3048)
			(stroke
				(width 0.1)
				(type default)
			)
			(layer "F.Fab")
		)
		(fp_line
			(start 0.12065 -0.3048)
			(end 0.67945 -0.3048)
			(stroke
				(width 0.1)
				(type default)
			)
			(layer "F.Fab")
		)
		(fp_line
			(start 0.120396 0.3048)
			(end 0.120396 0.2794)
			(stroke
				(width 0.1)
				(type default)
			)
			(layer "F.Fab")
		)
		(fp_line
			(start 0.120396 0.2794)
			(end -0.12065 0.2794)
			(stroke
				(width 0.1)
				(type default)
			)
			(layer "F.Fab")
		)
		(fp_line
			(start -0.12065 0.3048)
			(end -0.67945 0.3048)
			(stroke
				(width 0.1)
				(type default)
			)
			(layer "F.Fab")
		)
		(fp_line
			(start -0.12065 0.2794)
			(end -0.12065 0.3048)
			(stroke
				(width 0.1)
				(type default)
			)
			(layer "F.Fab")
		)
		(fp_line
			(start -0.12065 -0.2794)
			(end 0.12065 -0.2794)
			(stroke
				(width 0.1)
				(type default)
			)
			(layer "F.Fab")
		)
		(fp_line
			(start -0.12065 -0.305054)
			(end -0.12065 -0.2794)
			(stroke
				(width 0.1)
				(type default)
			)
			(layer "F.Fab")
		)
		(fp_line
			(start -0.67945 0.3048)
			(end -0.67945 -0.305054)
			(stroke
				(width 0.1)
				(type default)
			)
			(layer "F.Fab")
		)
		(fp_line
			(start -0.67945 -0.305054)
			(end -0.12065 -0.305054)
			(stroke
				(width 0.1)
				(type default)
			)
			(layer "F.Fab")
		)
		(pad "1" smd circle
			(at -0.40005 0 180)
			(size 0 0)
			(layers "F.Cu" "F.Mask" "F.Paste")
			(net "P3V3_OCP_GATE_2")
		)
		(pad "2" smd circle
			(at 0.40005 0 180)
			(size 0 0)
			(layers "F.Cu" "F.Mask" "F.Paste")
			(net "GND")
		)
	)
	(footprint ""
		(layer "F.Cu")
		(at 306.831746 -416.899344 -90)
		(property "Reference" "C6504"
			(at 0 0 270)
			(layer "F.SilkS")
			(hide yes)
			(effects
				(font
					(size 1.27 1.27)
				)
			)
		)
		(property "Value" ""
			(at 0 0 270)
			(layer "F.Fab")
			(effects
				(font
					(size 1.27 1.27)
				)
			)
		)
		(duplicate_pad_numbers_are_jumpers no)
		(fp_line
			(start -0.299974 0.150114)
			(end -0.299974 -0.150114)
			(stroke
				(width 0.1)
				(type default)
			)
			(layer "F.Fab")
		)
		(fp_line
			(start 0.299974 0.150114)
			(end -0.299974 0.150114)
			(stroke
				(width 0.1)
				(type default)
			)
			(layer "F.Fab")
		)
		(fp_line
			(start -0.299974 -0.150114)
			(end 0.299974 -0.150114)
			(stroke
				(width 0.1)
				(type default)
			)
			(layer "F.Fab")
		)
		(fp_line
			(start 0.299974 -0.150114)
			(end 0.299974 0.150114)
			(stroke
				(width 0.1)
				(type default)
			)
			(layer "F.Fab")
		)
		(pad "1" smd rect
			(at -0.2667 0 270)
			(size 0.3048 0.381)
			(layers "F.Cu" "F.Mask" "F.Paste")
			(net "P5E_CPU0_P0_TX_BUF_C_DN<1>")
		)
		(pad "2" smd rect
			(at 0.2667 0 270)
			(size 0.3048 0.381)
			(layers "F.Cu" "F.Mask" "F.Paste")
			(net "P5E_CPU0_P0_TX_BUF_DN<1>")
		)
	)
	(footprint ""
		(layer "F.Cu")
		(at 159.18307 -74.75347 90)
		(property "Reference" "R116"
			(at 0 0 90)
			(layer "F.SilkS")
			(hide yes)
			(effects
				(font
					(size 1.27 1.27)
				)
			)
		)
		(property "Value" ""
			(at 0 0 90)
			(layer "F.Fab")
			(effects
				(font
					(size 1.27 1.27)
				)
			)
		)
		(duplicate_pad_numbers_are_jumpers no)
		(fp_line
			(start 0.7874 -0.4064)
			(end 0.7874 0.4064)
			(stroke
				(width 0.1524)
				(type default)
			)
			(layer "F.SilkS")
		)
		(fp_line
			(start -0.7874 -0.4064)
			(end 0.7874 -0.4064)
			(stroke
				(width 0.1524)
				(type default)
			)
			(layer "F.SilkS")
		)
		(fp_line
			(start 0.7874 0.4064)
			(end -0.7874 0.4064)
			(stroke
				(width 0.1524)
				(type default)
			)
			(layer "F.SilkS")
		)
		(fp_line
			(start -0.7874 0.4064)
			(end -0.7874 -0.4064)
			(stroke
				(width 0.1524)
				(type default)
			)
			(layer "F.SilkS")
		)
		(fp_line
			(start -0.12065 -0.305054)
			(end -0.12065 -0.2794)
			(stroke
				(width 0.1)
				(type default)
			)
			(layer "F.Fab")
		)
		(fp_line
			(start -0.67945 -0.305054)
			(end -0.12065 -0.305054)
			(stroke
				(width 0.1)
				(type default)
			)
			(layer "F.Fab")
		)
		(fp_line
			(start 0.67945 -0.3048)
			(end 0.67945 0.3048)
			(stroke
				(width 0.1)
				(type default)
			)
			(layer "F.Fab")
		)
		(fp_line
			(start 0.12065 -0.3048)
			(end 0.67945 -0.3048)
			(stroke
				(width 0.1)
				(type default)
			)
			(layer "F.Fab")
		)
		(fp_line
			(start 0.12065 -0.2794)
			(end 0.12065 -0.3048)
			(stroke
				(width 0.1)
				(type default)
			)
			(layer "F.Fab")
		)
		(fp_line
			(start -0.12065 -0.2794)
			(end 0.12065 -0.2794)
			(stroke
				(width 0.1)
				(type default)
			)
			(layer "F.Fab")
		)
		(fp_line
			(start 0.120396 0.2794)
			(end -0.12065 0.2794)
			(stroke
				(width 0.1)
				(type default)
			)
			(layer "F.Fab")
		)
		(fp_line
			(start -0.12065 0.2794)
			(end -0.12065 0.3048)
			(stroke
				(width 0.1)
				(type default)
			)
			(layer "F.Fab")
		)
		(fp_line
			(start 0.67945 0.3048)
			(end 0.120396 0.3048)
			(stroke
				(width 0.1)
				(type default)
			)
			(layer "F.Fab")
		)
		(fp_line
			(start 0.120396 0.3048)
			(end 0.120396 0.2794)
			(stroke
				(width 0.1)
				(type default)
			)
			(layer "F.Fab")
		)
		(fp_line
			(start -0.12065 0.3048)
			(end -0.67945 0.3048)
			(stroke
				(width 0.1)
				(type default)
			)
			(layer "F.Fab")
		)
		(fp_line
			(start -0.67945 0.3048)
			(end -0.67945 -0.305054)
			(stroke
				(width 0.1)
				(type default)
			)
			(layer "F.Fab")
		)
		(pad "1" smd circle
			(at -0.40005 0 90)
			(size 0 0)
			(layers "F.Cu" "F.Mask" "F.Paste")
			(net "IRQ_OCP_SFF_WAKE_BUF_N")
		)
		(pad "2" smd circle
			(at 0.40005 0 90)
			(size 0 0)
			(layers "F.Cu" "F.Mask" "F.Paste")
			(net "IRQ_LVC3_WAKE_N")
		)
	)
)
